(kicad_pcb
	(version 20260206)
	(generator "pcbnew")
	(generator_version "10.0")
	(general
		(thickness 1.6)
		(legacy_teardrops no)
	)
	(paper "A4")
	(title_block
		(title "Wiwynn_Tioga_Pass_MB.brd")
		(comment 1 "Tioga Pass / footprints 625-631 of 4770")
	)
	(layers
		(0 "F.Cu" signal "TOP")
		(4 "In1.Cu" signal "L2GND")
		(6 "In2.Cu" signal "L3")
		(8 "In3.Cu" signal "L4GND")
		(10 "In4.Cu" signal "L5")
		(12 "In5.Cu" signal "L6GND")
		(14 "In6.Cu" signal "L7VCC")
		(16 "In7.Cu" signal "L8VCC")
		(18 "In8.Cu" signal "L9GND")
		(20 "In9.Cu" signal "L10")
		(22 "In10.Cu" signal "L11GND")
		(24 "In11.Cu" signal "L12")
		(26 "In12.Cu" signal "L13GND")
		(2 "B.Cu" signal "BOTTOM")
		(9 "F.Adhes" user "F.Adhesive")
		(11 "B.Adhes" user "B.Adhesive")
		(13 "F.Paste" user "Package Geometry/Pastemask Top")
		(15 "B.Paste" user "Package Geometry/Pastemask Bottom")
		(5 "F.SilkS" user "Ref Des/Silkscreen Top")
		(7 "B.SilkS" user "Ref Des/Silkscreen Bottom")
		(1 "F.Mask" user "Board Geometry/Soldermask Top")
		(3 "B.Mask" user "Board Geometry/Soldermask Bottom")
		(17 "Dwgs.User" user "User.Drawings")
		(19 "Cmts.User" user "User.Comments")
		(21 "Eco1.User" user "User.Eco1")
		(23 "Eco2.User" user "User.Eco2")
		(25 "Edge.Cuts" user "Board Geometry/Outline")
		(27 "Margin" user)
		(31 "F.CrtYd" user "Package Geometry/Place Bound Top")
		(29 "B.CrtYd" user "Package Geometry/Place Bound Bottom")
		(35 "F.Fab" user "Ref Des/Assembly Top")
		(33 "B.Fab" user "Ref Des/Assembly Bottom")
	)
	(footprint ""
		(layer "F.Cu")
		(at 399.48231 -61.962538 -90)
		(property "Reference" "C8E4"
			(at 0 0 270)
			(layer "F.SilkS")
			(hide yes)
			(effects
				(font
					(size 1.27 1.27)
				)
			)
		)
		(property "Value" "*"
			(at 0 -9.7155 270)
			(unlocked yes)
			(layer "F.Fab")
			(hide yes)
			(effects
				(font
					(size 1.27 1.016)
					(thickness 0.1524)
				)
			)
		)
		(property "Device Type" "ST220U10VDM-LGP_SMD-TCG-ST220UA"
			(at 0 -11.2395 270)
			(unlocked yes)
			(layer "F.Fab")
			(hide yes)
			(effects
				(font
					(size 1.27 1.016)
					(thickness 0.1524)
				)
			)
		)
		(duplicate_pad_numbers_are_jumpers no)
		(fp_line
			(start -2.286 4.8768)
			(end -2.286 2.032)
			(stroke
				(width 0.1524)
				(type default)
			)
			(layer "F.SilkS")
		)
		(fp_line
			(start 2.286 4.8768)
			(end -2.286 4.8768)
			(stroke
				(width 0.1524)
				(type default)
			)
			(layer "F.SilkS")
		)
		(fp_line
			(start 2.286 2.032)
			(end 2.286 4.8768)
			(stroke
				(width 0.1524)
				(type default)
			)
			(layer "F.SilkS")
		)
		(fp_line
			(start 2.286 -2.032)
			(end 2.286 -4.8768)
			(stroke
				(width 0.1524)
				(type default)
			)
			(layer "F.SilkS")
		)
		(fp_line
			(start 2.1082 -4.699)
			(end -2.1082 -4.699)
			(stroke
				(width 0.508)
				(type default)
			)
			(layer "F.SilkS")
		)
		(fp_line
			(start -2.286 -4.8768)
			(end -2.286 -2.032)
			(stroke
				(width 0.1524)
				(type default)
			)
			(layer "F.SilkS")
		)
		(fp_line
			(start 2.286 -4.8768)
			(end -2.286 -4.8768)
			(stroke
				(width 0.1524)
				(type default)
			)
			(layer "F.SilkS")
		)
		(fp_rect
			(start -2.1463 3.6449)
			(end 2.1463 -3.6449)
			(stroke
				(width 0)
				(type default)
			)
			(fill no)
			(layer "F.CrtYd")
		)
		(fp_poly
			(pts
				(xy -2.54 4.953) (xy -2.54 4.2926) (xy -3.81 4.2926) (xy -3.81 -4.2926) (xy -2.54 -4.2926) (xy -2.54 -4.953)
				(xy 2.54 -4.953) (xy 2.54 -4.2926) (xy 3.81 -4.2926) (xy 3.81 -1.6256) (xy 2.1463 -1.6256) (xy 2.1463 -3.6449)
				(xy -2.1463 -3.6449) (xy -2.1463 3.6449) (xy 2.1463 3.6449) (xy 2.1463 -1.6129) (xy 3.81 -1.6129)
				(xy 3.81 4.2926) (xy 2.54 4.2926) (xy 2.54 4.953)
			)
			(stroke
				(width 0)
				(type default)
			)
			(fill no)
			(layer "F.CrtYd")
		)
		(fp_rect
			(start -2.54 4.953)
			(end 2.54 -4.953)
			(stroke
				(width 0)
				(type default)
			)
			(fill no)
			(layer "F.Fab")
		)
		(fp_rect
			(start -3.81 4.2926)
			(end -2.54 -4.2926)
			(stroke
				(width 0)
				(type default)
			)
			(fill no)
			(layer "F.Fab")
		)
		(fp_rect
			(start 2.54 4.2926)
			(end 3.81 -4.2926)
			(stroke
				(width 0)
				(type default)
			)
			(fill no)
			(layer "F.Fab")
		)
		(pad "1" smd rect
			(at 0 -3.1496 270)
			(size 2.413 2.286)
			(layers "F.Cu" "F.Mask" "F.Paste")
			(net "P5V_STBY")
		)
		(pad "2" smd rect
			(at 0 3.1496 270)
			(size 2.413 2.286)
			(layers "F.Cu" "F.Mask" "F.Paste")
			(net "GND")
		)
		(zone
			(layer "F.Cu")
			(hatch none 0.5)
			(connect_pads
				(clearance 0)
			)
			(min_thickness 0.25)
			(keepout
				(tracks allowed)
				(vias not_allowed)
				(pads allowed)
				(copperpour not_allowed)
				(footprints allowed)
			)
			(placement
				(enabled no)
				(sheetname "")
			)
			(fill
				(thermal_gap 0.5)
				(thermal_bridge_width 0.5)
				(island_removal_mode 0)
			)
			(polygon
				(pts
					(xy 394.88491 -63.473838) (xy 394.88491 -60.451238) (xy 397.78051 -60.451238) (xy 398.11071 -60.451238)
					(xy 398.11071 -63.473838) (xy 397.78051 -63.473838)
				)
			)
		)
		(zone
			(layer "F.Cu")
			(hatch none 0.5)
			(connect_pads
				(clearance 0)
			)
			(min_thickness 0.25)
			(keepout
				(tracks allowed)
				(vias not_allowed)
				(pads allowed)
				(copperpour not_allowed)
				(footprints allowed)
			)
			(placement
				(enabled no)
				(sheetname "")
			)
			(fill
				(thermal_gap 0.5)
				(thermal_bridge_width 0.5)
				(island_removal_mode 0)
			)
			(polygon
				(pts
					(xy 401.17141 -60.451238) (xy 404.07971 -60.451238) (xy 404.07971 -63.473838) (xy 401.18411 -63.473838)
					(xy 400.85391 -63.473838) (xy 400.85391 -60.451238)
				)
			)
		)
	)
	(footprint ""
		(layer "F.Cu")
		(at 412.632652 -134.747 180)
		(property "Reference" "R8B1"
			(at 0 0 180)
			(layer "F.SilkS")
			(hide yes)
			(effects
				(font
					(size 1.27 1.27)
				)
			)
		)
		(property "Value" ""
			(at 0 0 180)
			(layer "F.Fab")
			(effects
				(font
					(size 1.27 1.27)
				)
			)
		)
		(duplicate_pad_numbers_are_jumpers no)
		(fp_poly
			(pts
				(xy -0.2794 -0.1016) (xy 0.2794 -0.1016) (xy 0.2794 0.9906) (xy -0.2794 0.9906)
			)
			(stroke
				(width 0)
				(type default)
			)
			(fill no)
			(layer "F.CrtYd")
		)
		(fp_line
			(start 0.2794 0.9906)
			(end 0.2794 -0.1016)
			(stroke
				(width 0.1)
				(type default)
			)
			(layer "F.Fab")
		)
		(fp_line
			(start 0.2794 -0.1016)
			(end -0.2794 -0.1016)
			(stroke
				(width 0.1)
				(type default)
			)
			(layer "F.Fab")
		)
		(fp_line
			(start -0.2794 0.9906)
			(end 0.2794 0.9906)
			(stroke
				(width 0.1)
				(type default)
			)
			(layer "F.Fab")
		)
		(fp_line
			(start -0.2794 -0.1016)
			(end -0.2794 0.9906)
			(stroke
				(width 0.1)
				(type default)
			)
			(layer "F.Fab")
		)
		(pad "1" smd rect
			(at 0 0 180)
			(size 0.508 0.508)
			(layers "F.Cu" "F.Mask" "F.Paste")
			(net "XDP_PCH_TCK1")
		)
		(pad "2" smd rect
			(at 0 0.889 180)
			(size 0.508 0.508)
			(layers "F.Cu" "F.Mask" "F.Paste")
			(net "GND")
		)
		(zone
			(layer "F.Cu")
			(hatch none 0.5)
			(connect_pads
				(clearance 0)
			)
			(min_thickness 0.25)
			(keepout
				(tracks not_allowed)
				(vias allowed)
				(pads allowed)
				(copperpour not_allowed)
				(footprints allowed)
			)
			(placement
				(enabled no)
				(sheetname "")
			)
			(fill
				(thermal_gap 0.5)
				(thermal_bridge_width 0.5)
				(island_removal_mode 0)
			)
			(polygon
				(pts
					(xy 412.886652 -135.382) (xy 412.378652 -135.382) (xy 412.378652 -135.001) (xy 412.886652 -135.001)
				)
			)
		)
		(zone
			(layer "F.Cu")
			(hatch none 0.5)
			(connect_pads
				(clearance 0)
			)
			(min_thickness 0.25)
			(keepout
				(tracks allowed)
				(vias not_allowed)
				(pads allowed)
				(copperpour not_allowed)
				(footprints allowed)
			)
			(placement
				(enabled no)
				(sheetname "")
			)
			(fill
				(thermal_gap 0.5)
				(thermal_bridge_width 0.5)
				(island_removal_mode 0)
			)
			(polygon
				(pts
					(xy 412.886652 -135.001) (xy 412.378652 -135.001) (xy 412.378652 -135.382) (xy 412.886652 -135.382)
				)
			)
		)
	)
	(footprint ""
		(layer "F.Cu")
		(at 406.516078 -120.271032 90)
		(property "Reference" "R1W18"
			(at -0.8382 -0.67818 90)
			(unlocked yes)
			(layer "F.SilkS")
			(effects
				(font
					(size 0.4064 0.254)
					(thickness 0.1524)
				)
				(justify left)
			)
		)
		(property "Value" ""
			(at 0 0 90)
			(layer "F.Fab")
			(effects
				(font
					(size 1.27 1.27)
				)
			)
		)
		(duplicate_pad_numbers_are_jumpers no)
		(fp_poly
			(pts
				(xy -0.2794 -0.1016) (xy 0.2794 -0.1016) (xy 0.2794 0.9906) (xy -0.2794 0.9906)
			)
			(stroke
				(width 0)
				(type default)
			)
			(fill no)
			(layer "F.CrtYd")
		)
		(fp_line
			(start 0.2794 -0.1016)
			(end -0.2794 -0.1016)
			(stroke
				(width 0.1)
				(type default)
			)
			(layer "F.Fab")
		)
		(fp_line
			(start -0.2794 -0.1016)
			(end -0.2794 0.9906)
			(stroke
				(width 0.1)
				(type default)
			)
			(layer "F.Fab")
		)
		(fp_line
			(start 0.2794 0.9906)
			(end 0.2794 -0.1016)
			(stroke
				(width 0.1)
				(type default)
			)
			(layer "F.Fab")
		)
		(fp_line
			(start -0.2794 0.9906)
			(end 0.2794 0.9906)
			(stroke
				(width 0.1)
				(type default)
			)
			(layer "F.Fab")
		)
		(pad "1" smd rect
			(at 0 0 90)
			(size 0.508 0.508)
			(layers "F.Cu" "F.Mask" "F.Paste")
			(net "USB2_P02_DP_R")
		)
		(pad "2" smd rect
			(at 0 0.889 90)
			(size 0.508 0.508)
			(layers "F.Cu" "F.Mask" "F.Paste")
			(net "USB2_P02_DP")
		)
		(zone
			(layer "F.Cu")
			(hatch none 0.5)
			(connect_pads
				(clearance 0)
			)
			(min_thickness 0.25)
			(keepout
				(tracks allowed)
				(vias not_allowed)
				(pads allowed)
				(copperpour not_allowed)
				(footprints allowed)
			)
			(placement
				(enabled no)
				(sheetname "")
			)
			(fill
				(thermal_gap 0.5)
				(thermal_bridge_width 0.5)
				(island_removal_mode 0)
			)
			(polygon
				(pts
					(xy 406.770078 -120.017032) (xy 406.770078 -120.525032) (xy 407.151078 -120.525032) (xy 407.151078 -120.017032)
				)
			)
		)
		(zone
			(layer "F.Cu")
			(hatch none 0.5)
			(connect_pads
				(clearance 0)
			)
			(min_thickness 0.25)
			(keepout
				(tracks not_allowed)
				(vias allowed)
				(pads allowed)
				(copperpour not_allowed)
				(footprints allowed)
			)
			(placement
				(enabled no)
				(sheetname "")
			)
			(fill
				(thermal_gap 0.5)
				(thermal_bridge_width 0.5)
				(island_removal_mode 0)
			)
			(polygon
				(pts
					(xy 407.151078 -120.017032) (xy 407.151078 -120.525032) (xy 406.770078 -120.525032) (xy 406.770078 -120.017032)
				)
			)
		)
	)
	(footprint ""
		(layer "F.Cu")
		(at 352.424238 -0.124206)
		(property "Reference" "R7G30"
			(at 0 0 0)
			(layer "F.SilkS")
			(hide yes)
			(effects
				(font
					(size 1.27 1.27)
				)
			)
		)
		(property "Value" ""
			(at 0 0 0)
			(layer "F.Fab")
			(effects
				(font
					(size 1.27 1.27)
				)
			)
		)
		(duplicate_pad_numbers_are_jumpers no)
		(fp_poly
			(pts
				(xy -0.2794 -0.1016) (xy 0.2794 -0.1016) (xy 0.2794 0.9906) (xy -0.2794 0.9906)
			)
			(stroke
				(width 0)
				(type default)
			)
			(fill no)
			(layer "F.CrtYd")
		)
		(fp_line
			(start -0.2794 -0.1016)
			(end -0.2794 0.9906)
			(stroke
				(width 0.1)
				(type default)
			)
			(layer "F.Fab")
		)
		(fp_line
			(start -0.2794 0.9906)
			(end 0.2794 0.9906)
			(stroke
				(width 0.1)
				(type default)
			)
			(layer "F.Fab")
		)
		(fp_line
			(start 0.2794 -0.1016)
			(end -0.2794 -0.1016)
			(stroke
				(width 0.1)
				(type default)
			)
			(layer "F.Fab")
		)
		(fp_line
			(start 0.2794 0.9906)
			(end 0.2794 -0.1016)
			(stroke
				(width 0.1)
				(type default)
			)
			(layer "F.Fab")
		)
		(pad "1" smd rect
			(at 0 0)
			(size 0.508 0.508)
			(layers "F.Cu" "F.Mask" "F.Paste")
			(net "VR_PVDDQ_ABC_PH2_OCSET")
		)
		(pad "2" smd rect
			(at 0 0.889)
			(size 0.508 0.508)
			(layers "F.Cu" "F.Mask" "F.Paste")
			(net "GND")
		)
		(zone
			(layer "F.Cu")
			(hatch none 0.5)
			(connect_pads
				(clearance 0)
			)
			(min_thickness 0.25)
			(keepout
				(tracks allowed)
				(vias not_allowed)
				(pads allowed)
				(copperpour not_allowed)
				(footprints allowed)
			)
			(placement
				(enabled no)
				(sheetname "")
			)
			(fill
				(thermal_gap 0.5)
				(thermal_bridge_width 0.5)
				(island_removal_mode 0)
			)
			(polygon
				(pts
					(xy 352.170238 0.129794) (xy 352.678238 0.129794) (xy 352.678238 0.510794) (xy 352.170238 0.510794)
				)
			)
		)
		(zone
			(layer "F.Cu")
			(hatch none 0.5)
			(connect_pads
				(clearance 0)
			)
			(min_thickness 0.25)
			(keepout
				(tracks not_allowed)
				(vias allowed)
				(pads allowed)
				(copperpour not_allowed)
				(footprints allowed)
			)
			(placement
				(enabled no)
				(sheetname "")
			)
			(fill
				(thermal_gap 0.5)
				(thermal_bridge_width 0.5)
				(island_removal_mode 0)
			)
			(polygon
				(pts
					(xy 352.170238 0.510794) (xy 352.678238 0.510794) (xy 352.678238 0.129794) (xy 352.170238 0.129794)
				)
			)
		)
	)
	(footprint ""
		(layer "F.Cu")
		(at 183.769 -65.024)
		(property "Reference" "R4D66"
			(at 0 0 0)
			(layer "F.SilkS")
			(hide yes)
			(effects
				(font
					(size 1.27 1.27)
				)
			)
		)
		(property "Value" ""
			(at 0 0 0)
			(layer "F.Fab")
			(effects
				(font
					(size 1.27 1.27)
				)
			)
		)
		(duplicate_pad_numbers_are_jumpers no)
		(fp_rect
			(start -0.2794 0.9906)
			(end 0.2794 -0.1016)
			(stroke
				(width 0)
				(type default)
			)
			(fill no)
			(layer "F.CrtYd")
		)
		(fp_line
			(start -0.2794 -0.1016)
			(end -0.2794 0.9906)
			(stroke
				(width 0.1)
				(type default)
			)
			(layer "F.Fab")
		)
		(fp_line
			(start -0.2794 0.9906)
			(end 0.2794 0.9906)
			(stroke
				(width 0.1)
				(type default)
			)
			(layer "F.Fab")
		)
		(fp_line
			(start 0.2794 -0.1016)
			(end -0.2794 -0.1016)
			(stroke
				(width 0.1)
				(type default)
			)
			(layer "F.Fab")
		)
		(fp_line
			(start 0.2794 0.9906)
			(end 0.2794 -0.1016)
			(stroke
				(width 0.1)
				(type default)
			)
			(layer "F.Fab")
		)
		(pad "1" smd rect
			(at 0 0)
			(size 0.508 0.508)
			(layers "F.Cu" "F.Mask" "F.Paste")
			(net "SVID_VDIO_PVCCIN_CPU0")
		)
		(pad "2" smd rect
			(at 0 0.889)
			(size 0.508 0.508)
			(layers "F.Cu" "F.Mask" "F.Paste")
			(net "SVID_DIO0_CPU0_R")
		)
		(zone
			(layer "F.Cu")
			(hatch none 0.5)
			(connect_pads
				(clearance 0)
			)
			(min_thickness 0.25)
			(keepout
				(tracks allowed)
				(vias not_allowed)
				(pads allowed)
				(copperpour not_allowed)
				(footprints allowed)
			)
			(placement
				(enabled no)
				(sheetname "")
			)
			(fill
				(thermal_gap 0.5)
				(thermal_bridge_width 0.5)
				(island_removal_mode 0)
			)
			(polygon
				(pts
					(xy 183.515 -64.389) (xy 184.023 -64.389) (xy 184.023 -64.77) (xy 183.515 -64.77)
				)
			)
		)
		(zone
			(layer "F.Cu")
			(hatch none 0.5)
			(connect_pads
				(clearance 0)
			)
			(min_thickness 0.25)
			(keepout
				(tracks not_allowed)
				(vias allowed)
				(pads allowed)
				(copperpour not_allowed)
				(footprints allowed)
			)
			(placement
				(enabled no)
				(sheetname "")
			)
			(fill
				(thermal_gap 0.5)
				(thermal_bridge_width 0.5)
				(island_removal_mode 0)
			)
			(polygon
				(pts
					(xy 183.515 -64.389) (xy 184.023 -64.389) (xy 184.023 -64.77) (xy 183.515 -64.77)
				)
			)
		)
	)
	(footprint ""
		(layer "F.Cu")
		(at 449.69938 -35.8775 90)
		(property "Reference" "R25W3"
			(at 0 0 90)
			(layer "F.SilkS")
			(hide yes)
			(effects
				(font
					(size 1.27 1.27)
				)
			)
		)
		(property "Value" "*"
			(at 0.064008 -4.108196 90)
			(unlocked yes)
			(layer "F.Fab")
			(hide yes)
			(effects
				(font
					(size 1.27 1.016)
					(thickness 0.1524)
				)
			)
		)
		(property "Device Type" "120R2F-GP_RCL_GP-120R2F-GP,64.A"
			(at 0.064008 -5.632196 90)
			(unlocked yes)
			(layer "F.Fab")
			(hide yes)
			(effects
				(font
					(size 1.27 1.016)
					(thickness 0.1524)
				)
			)
		)
		(duplicate_pad_numbers_are_jumpers no)
		(fp_line
			(start 0.508 -0.9398)
			(end -0.508 -0.9398)
			(stroke
				(width 0.1524)
				(type default)
			)
			(layer "F.SilkS")
		)
		(fp_line
			(start -0.508 -0.9398)
			(end -0.508 0.9398)
			(stroke
				(width 0.1524)
				(type default)
			)
			(layer "F.SilkS")
		)
		(fp_rect
			(start -0.508 0.9398)
			(end 0.508 -0.9398)
			(stroke
				(width 0)
				(type default)
			)
			(fill no)
			(layer "F.CrtYd")
		)
		(fp_rect
			(start -0.508 0.9398)
			(end 0.508 -0.9398)
			(stroke
				(width 0)
				(type default)
			)
			(fill no)
			(layer "F.Fab")
		)
		(pad "1" smd custom
			(at 0 -0.4445 90)
			(size 0.1397 0.1397)
			(layers "F.Cu" "F.Mask" "F.Paste")
			(net "GND")
			(options
				(clearance outline)
				(anchor circle)
			)
			(primitives
				(gr_poly
					(pts
						(arc
							(start -0.1778 -0.2794)
							(mid -0.249642 -0.249642)
							(end -0.2794 -0.1778)
						)
						(arc
							(start -0.2794 0.1778)
							(mid -0.249642 0.249642)
							(end -0.1778 0.2794)
						)
						(arc
							(start 0.1778 0.2794)
							(mid 0.249642 0.249642)
							(end 0.2794 0.1778)
						)
						(arc
							(start 0.2794 -0.1778)
							(mid 0.249642 -0.249642)
							(end 0.1778 -0.2794)
						)
					)
					(width 0)
					(fill yes)
				)
			)
		)
		(pad "2" smd custom
			(at 0 0.4445 90)
			(size 0.1397 0.1397)
			(layers "F.Cu" "F.Mask" "F.Paste")
			(net "BMC_M_RST_N")
			(options
				(clearance outline)
				(anchor circle)
			)
			(primitives
				(gr_poly
					(pts
						(arc
							(start -0.1778 -0.2794)
							(mid -0.249642 -0.249642)
							(end -0.2794 -0.1778)
						)
						(arc
							(start -0.2794 0.1778)
							(mid -0.249642 0.249642)
							(end -0.1778 0.2794)
						)
						(arc
							(start 0.1778 0.2794)
							(mid 0.249642 0.249642)
							(end 0.2794 0.1778)
						)
						(arc
							(start 0.2794 -0.1778)
							(mid 0.249642 -0.249642)
							(end 0.1778 -0.2794)
						)
					)
					(width 0)
					(fill yes)
				)
			)
		)
	)
	(footprint ""
		(layer "F.Cu")
		(at 28.7274 -104.5718 90)
		(property "Reference" "R1C33"
			(at 0 0 90)
			(layer "F.SilkS")
			(hide yes)
			(effects
				(font
					(size 1.27 1.27)
				)
			)
		)
		(property "Value" ""
			(at 0 0 90)
			(layer "F.Fab")
			(effects
				(font
					(size 1.27 1.27)
				)
			)
		)
		(duplicate_pad_numbers_are_jumpers no)
		(fp_poly
			(pts
				(xy -0.2794 -0.1016) (xy 0.2794 -0.1016) (xy 0.2794 0.9906) (xy -0.2794 0.9906)
			)
			(stroke
				(width 0)
				(type default)
			)
			(fill no)
			(layer "F.CrtYd")
		)
		(fp_line
			(start 0.2794 -0.1016)
			(end -0.2794 -0.1016)
			(stroke
				(width 0.1)
				(type default)
			)
			(layer "F.Fab")
		)
		(fp_line
			(start -0.2794 -0.1016)
			(end -0.2794 0.9906)
			(stroke
				(width 0.1)
				(type default)
			)
			(layer "F.Fab")
		)
		(fp_line
			(start 0.2794 0.9906)
			(end 0.2794 -0.1016)
			(stroke
				(width 0.1)
				(type default)
			)
			(layer "F.Fab")
		)
		(fp_line
			(start -0.2794 0.9906)
			(end 0.2794 0.9906)
			(stroke
				(width 0.1)
				(type default)
			)
			(layer "F.Fab")
		)
		(pad "1" smd rect
			(at 0 0 90)
			(size 0.508 0.508)
			(layers "F.Cu" "F.Mask" "F.Paste")
			(net "GND")
		)
		(pad "2" smd rect
			(at 0 0.889 90)
			(size 0.508 0.508)
			(layers "F.Cu" "F.Mask" "F.Paste")
			(net "PD_PIROM_CPU1_ADDR1")
		)
		(zone
			(layer "F.Cu")
			(hatch none 0.5)
			(connect_pads
				(clearance 0)
			)
			(min_thickness 0.25)
			(keepout
				(tracks allowed)
				(vias not_allowed)
				(pads allowed)
				(copperpour not_allowed)
				(footprints allowed)
			)
			(placement
				(enabled no)
				(sheetname "")
			)
			(fill
				(thermal_gap 0.5)
				(thermal_bridge_width 0.5)
				(island_removal_mode 0)
			)
			(polygon
				(pts
					(xy 28.9814 -104.3178) (xy 28.9814 -104.8258) (xy 29.3624 -104.8258) (xy 29.3624 -104.3178)
				)
			)
		)
		(zone
			(layer "F.Cu")
			(hatch none 0.5)
			(connect_pads
				(clearance 0)
			)
			(min_thickness 0.25)
			(keepout
				(tracks not_allowed)
				(vias allowed)
				(pads allowed)
				(copperpour not_allowed)
				(footprints allowed)
			)
			(placement
				(enabled no)
				(sheetname "")
			)
			(fill
				(thermal_gap 0.5)
				(thermal_bridge_width 0.5)
				(island_removal_mode 0)
			)
			(polygon
				(pts
					(xy 29.3624 -104.3178) (xy 29.3624 -104.8258) (xy 28.9814 -104.8258) (xy 28.9814 -104.3178)
				)
			)
		)
	)
)
